# discovery-power-board-v1-revB — discovery.net (kicad-netlist(.net))
(export (version D)
  (design
    (source C:\Users\<user>\Documents\GitHub\Discovery\electrical\power_board_v1_revB\design_files\discovery.sch)
    (date "10/04/2019 15:26:56")
    (tool "Eeschema (5.0.1)-3")
    (sheet (number 1) (name /) 
      (title_block
        (title)
        (company)
        (rev)
        (date)
        (source discovery.sch)
        (comment (number 1) (value ""))
        (comment (number 2) (value ""))
        (comment (number 3) (value ""))
        (comment (number 4) (value "")))))
  (components
    (comp (ref J1)
      (value Conn_02x04_CPU)
      (footprint discovery:CONN_02x04_4.2mm)
      (datasheet ~)
      (libsource (lib Connector_Generic) (part Conn_02x04_Counter_Clockwise) (description "Generic connector, double row, 02x04, counter clockwise pin numbering scheme (similar to DIP packge numbering), script generated (kicad-library-utils/schlib/autogen/connector/)"))
      (sheetpath (names /) )
      )
    (comp (ref J3)
      (value Conn_02x04_CPU)
      (footprint discovery:CONN_02x04_4.2mm)
      (datasheet ~)
      (libsource (lib Connector_Generic) (part Conn_02x04_Counter_Clockwise) (description "Generic connector, double row, 02x04, counter clockwise pin numbering scheme (similar to DIP packge numbering), script generated (kicad-library-utils/schlib/autogen/connector/)"))
      (sheetpath (names /) )
      )
    (comp (ref W1)
      (value "Fixing hole")
      (footprint discovery:FixingPoint_Plated_Hole_D4.0mm)
      (datasheet ~)
      (libsource (lib Connector) (part TestPoint) (description "test point"))
      (sheetpath (names /) )
      )
    (comp (ref W2)
      (value "Fixing hole")
      (footprint discovery:FixingPoint_Plated_Hole_D4.0mm)
      (datasheet ~)
      (libsource (lib Connector) (part TestPoint) (description "test point"))
      (sheetpath (names /) )
      )
    (comp (ref W3)
      (value "Fixing hole")
      (footprint discovery:FixingPoint_Plated_Hole_D4.0mm)
      (datasheet ~)
      (libsource (lib Connector) (part TestPoint) (description "test point"))
      (sheetpath (names /) )
      )
    (comp (ref W4)
      (value "Fixing hole")
      (footprint discovery:FixingPoint_Plated_Hole_D4.0mm)
      (datasheet ~)
      (libsource (lib Connector) (part TestPoint) (description "test point"))
      (sheetpath (names /) )
      )
    (comp (ref W5)
      (value "Cable hole")
      (footprint discovery:fixing_hole)
      (datasheet ~)
      (libsource (lib Connector) (part TestPoint) (description "test point"))
      (sheetpath (names /) )
      )
    (comp (ref W6)
      (value "Cable hole")
      (footprint discovery:fixing_hole)
      (datasheet ~)
      (libsource (lib Connector) (part TestPoint) (description "test point"))
      (sheetpath (names /) )
      )
    (comp (ref W7)
      (value "Cable hole")
      (footprint discovery:fixing_hole)
      (datasheet ~)
      (libsource (lib Connector) (part TestPoint) (description "test point"))
      (sheetpath (names /) )
      )
    (comp (ref W12)
      (value "Cable hole")
      (footprint discovery:fixing_hole)
      (datasheet ~)
      (libsource (lib Connector) (part TestPoint) (description "test point"))
      (sheetpath (names /) )
      )
    (comp (ref W8)
      (value "Cable hole")
      (footprint discovery:fixing_hole)
      (datasheet ~)
      (libsource (lib Connector) (part TestPoint) (description "test point"))
      (sheetpath (names /) )
      )
    (comp (ref W9)
      (value "Cable hole")
      (footprint discovery:fixing_hole)
      (datasheet ~)
      (libsource (lib Connector) (part TestPoint) (description "test point"))
      (sheetpath (names /) )
      )
    (comp (ref W10)
      (value "Cable hole")
      (footprint discovery:fixing_hole)
      (datasheet ~)
      (libsource (lib Connector) (part TestPoint) (description "test point"))
      (sheetpath (names /) )
      )
    (comp (ref W11)
      (value "Cable hole")
      (footprint discovery:fixing_hole)
      (datasheet ~)
      (libsource (lib Connector) (part TestPoint) (description "test point"))
      (sheetpath (names /) )
      )
    (comp (ref J2)
      (value Conn_02x03_PCIe)
      (footprint discovery:CONN_02x03_4.2mm)
      (datasheet ~)
      (libsource (lib Connector_Generic) (part Conn_02x03_Counter_Clockwise) (description "Generic connector, double row, 02x03, counter clockwise pin numbering scheme (similar to DIP packge numbering), script generated (kicad-library-utils/schlib/autogen/connector/)"))
      (sheetpath (names /) )
      )
    (comp (ref J4)
      (value Conn_02x03_PCIe)
      (footprint discovery:CONN_02x03_4.2mm)
      (datasheet ~)
      (libsource (lib Connector_Generic) (part Conn_02x03_Counter_Clockwise) (description "Generic connector, double row, 02x03, counter clockwise pin numbering scheme (similar to DIP packge numbering), script generated (kicad-library-utils/schlib/autogen/connector/)"))
      (sheetpath (names /) )
      )
    (comp (ref J5)
      (value Conn_02x03_PCIe)
      (footprint discovery:CONN_02x03_4.2mm)
      (datasheet ~)
      (libsource (lib Connector_Generic) (part Conn_02x03_Counter_Clockwise) (description "Generic connector, double row, 02x03, counter clockwise pin numbering scheme (similar to DIP packge numbering), script generated (kicad-library-utils/schlib/autogen/connector/)"))
      (sheetpath (names /) )
      )
    (comp (ref J6)
      (value Conn_02x03_PCIe)
      (footprint discovery:CONN_02x03_4.2mm)
      (datasheet ~)
      (libsource (lib Connector_Generic) (part Conn_02x03_Counter_Clockwise) (description "Generic connector, double row, 02x03, counter clockwise pin numbering scheme (similar to DIP packge numbering), script generated (kicad-library-utils/schlib/autogen/connector/)"))
      (sheetpath (names /) )
      ))
  (libparts
    (libpart (lib Connector) (part TestPoint)
      (description "test point")
      (docs ~)
      (footprints
        (fp Pin*)
        (fp Test*))
      (fields
        (field (name Reference) TP)
        (field (name Value) TestPoint))
      (pins
        (pin (num 1) (name 1) (type passive))))
    (libpart (lib Connector_Generic) (part Conn_02x03_Counter_Clockwise)
      (description "Generic connector, double row, 02x03, counter clockwise pin numbering scheme (similar to DIP packge numbering), script generated (kicad-library-utils/schlib/autogen/connector/)")
      (docs ~)
      (footprints
        (fp Connector*:*_2x??_*))
      (fields
        (field (name Reference) J)
        (field (name Value) Conn_02x03_Counter_Clockwise))
      (pins
        (pin (num 1) (name Pin_1) (type passive))
        (pin (num 2) (name Pin_2) (type passive))
        (pin (num 3) (name Pin_3) (type passive))
        (pin (num 4) (name Pin_4) (type passive))
        (pin (num 5) (name Pin_5) (type passive))
        (pin (num 6) (name Pin_6) (type passive))))
    (libpart (lib Connector_Generic) (part Conn_02x04_Counter_Clockwise)
      (description "Generic connector, double row, 02x04, counter clockwise pin numbering scheme (similar to DIP packge numbering), script generated (kicad-library-utils/schlib/autogen/connector/)")
      (docs ~)
      (footprints
        (fp Connector*:*_2x??_*))
      (fields
        (field (name Reference) J)
        (field (name Value) Conn_02x04_Counter_Clockwise))
      (pins
        (pin (num 1) (name Pin_1) (type passive))
        (pin (num 2) (name Pin_2) (type passive))
        (pin (num 3) (name Pin_3) (type passive))
        (pin (num 4) (name Pin_4) (type passive))
        (pin (num 5) (name Pin_5) (type passive))
        (pin (num 6) (name Pin_6) (type passive))
        (pin (num 7) (name Pin_7) (type passive))
        (pin (num 8) (name Pin_8) (type passive)))))
  (libraries
    (library (logical Connector)
      (uri "C:\\Program Files\\KiCad\\share\\kicad\\library/Connector.lib"))
    (library (logical Connector_Generic)
      (uri "C:\\Program Files\\KiCad\\share\\kicad\\library/Connector_Generic.lib")))
  (nets
    (net (code 1) (name +12V)
      (node (ref J5) (pin 3))
      (node (ref J5) (pin 2))
      (node (ref J5) (pin 1))
      (node (ref W8) (pin 1))
      (node (ref W6) (pin 1))
      (node (ref J1) (pin 5))
      (node (ref J1) (pin 6))
      (node (ref J1) (pin 7))
      (node (ref J1) (pin 8))
      (node (ref J3) (pin 8))
      (node (ref J3) (pin 7))
      (node (ref J3) (pin 6))
      (node (ref J3) (pin 5))
      (node (ref W7) (pin 1))
      (node (ref J2) (pin 3))
      (node (ref J2) (pin 2))
      (node (ref J2) (pin 1))
      (node (ref J4) (pin 3))
      (node (ref J4) (pin 2))
      (node (ref J4) (pin 1))
      (node (ref W5) (pin 1))
      (node (ref J6) (pin 3))
      (node (ref J6) (pin 2))
      (node (ref J6) (pin 1)))
    (net (code 2) (name GND)
      (node (ref W3) (pin 1))
      (node (ref W11) (pin 1))
      (node (ref W4) (pin 1))
      (node (ref W10) (pin 1))
      (node (ref W12) (pin 1))
      (node (ref W1) (pin 1))
      (node (ref J1) (pin 1))
      (node (ref W2) (pin 1))
      (node (ref W9) (pin 1))
      (node (ref J2) (pin 4))
      (node (ref J2) (pin 6))
      (node (ref J6) (pin 4))
      (node (ref J6) (pin 5))
      (node (ref J6) (pin 6))
      (node (ref J4) (pin 6))
      (node (ref J4) (pin 4))
      (node (ref J4) (pin 5))
      (node (ref J2) (pin 5))
      (node (ref J3) (pin 1))
      (node (ref J3) (pin 2))
      (node (ref J3) (pin 3))
      (node (ref J3) (pin 4))
      (node (ref J1) (pin 2))
      (node (ref J1) (pin 3))
      (node (ref J1) (pin 4))
      (node (ref J5) (pin 5))
      (node (ref J5) (pin 4))
      (node (ref J5) (pin 6)))))